(kicad_pcb
	(version 20260206)
	(generator "pcbnew")
	(generator_version "10.0")
	(general
		(thickness 1.6)
		(legacy_teardrops no)
	)
	(paper "A4")
	(title_block
		(title "Bryce Canyon_R.DPB_16317-1_OCP.brd")
		(comment 1 "Bryce Canyon / footprints 1476-1482 of 2099")
	)
	(layers
		(0 "F.Cu" signal "TOP")
		(4 "In1.Cu" signal "L2GND")
		(6 "In2.Cu" signal "L3")
		(8 "In3.Cu" signal "L4VCC")
		(10 "In4.Cu" signal "L5VCC")
		(12 "In5.Cu" signal "L6")
		(14 "In6.Cu" signal "L7GND")
		(2 "B.Cu" signal "BOTTOM")
		(9 "F.Adhes" user "F.Adhesive")
		(11 "B.Adhes" user "B.Adhesive")
		(13 "F.Paste" user "Package Geometry/Pastemask Top")
		(15 "B.Paste" user "Package Geometry/Pastemask Bottom")
		(5 "F.SilkS" user "Ref Des/Silkscreen Top")
		(7 "B.SilkS" user "Ref Des/Silkscreen Bottom")
		(1 "F.Mask" user "Board Geometry/Soldermask Top")
		(3 "B.Mask" user "Board Geometry/Soldermask Bottom")
		(17 "Dwgs.User" user "User.Drawings")
		(19 "Cmts.User" user "User.Comments")
		(21 "Eco1.User" user "User.Eco1")
		(23 "Eco2.User" user "User.Eco2")
		(25 "Edge.Cuts" user "Board Geometry/Outline")
		(27 "Margin" user)
		(31 "F.CrtYd" user "Package Geometry/Place Bound Top")
		(29 "B.CrtYd" user "Package Geometry/Place Bound Bottom")
		(35 "F.Fab" user "Ref Des/Assembly Top")
		(33 "B.Fab" user "Ref Des/Assembly Bottom")
	)
	(footprint ""
		(layer "F.Cu")
		(at 222.123 -203.962 -90)
		(property "Reference" "R51"
			(at 0 0 270)
			(layer "F.SilkS")
			(hide yes)
			(effects
				(font
					(size 1.27 1.27)
				)
			)
		)
		(property "Value" "4K7R2F-GP"
			(at 0.064008 -3.993896 270)
			(unlocked yes)
			(layer "F.Fab")
			(hide yes)
			(effects
				(font
					(size 1.016 1.016)
					(thickness 0.1524)
				)
			)
		)
		(property "Device Type" "R402H16"
			(at 0.064008 -5.517896 270)
			(unlocked yes)
			(layer "F.Fab")
			(hide yes)
			(effects
				(font
					(size 1.016 1.016)
					(thickness 0.1524)
				)
			)
		)
		(duplicate_pad_numbers_are_jumpers no)
		(fp_line
			(start -0.508 -0.9398)
			(end -0.508 0.9398)
			(stroke
				(width 0.1524)
				(type default)
			)
			(layer "F.SilkS")
		)
		(fp_line
			(start 0.508 -0.9398)
			(end -0.508 -0.9398)
			(stroke
				(width 0.1524)
				(type default)
			)
			(layer "F.SilkS")
		)
		(fp_rect
			(start -0.508 0.9398)
			(end 0.508 -0.9398)
			(stroke
				(width 0)
				(type default)
			)
			(fill no)
			(layer "F.CrtYd")
		)
		(fp_rect
			(start -0.508 0.9398)
			(end 0.508 -0.9398)
			(stroke
				(width 0)
				(type default)
			)
			(fill no)
			(layer "F.Fab")
		)
		(pad "1" smd custom
			(at 0 -0.4445 270)
			(size 0.1397 0.1397)
			(layers "F.Cu" "F.Mask" "F.Paste")
			(net "P3V3_STBY_B")
			(options
				(clearance outline)
				(anchor circle)
			)
			(primitives
				(gr_poly
					(pts
						(arc
							(start -0.1778 -0.2794)
							(mid -0.249642 -0.249642)
							(end -0.2794 -0.1778)
						)
						(arc
							(start -0.2794 0.1778)
							(mid -0.249642 0.249642)
							(end -0.1778 0.2794)
						)
						(arc
							(start 0.1778 0.2794)
							(mid 0.249642 0.249642)
							(end 0.2794 0.1778)
						)
						(arc
							(start 0.2794 -0.1778)
							(mid 0.249642 -0.249642)
							(end 0.1778 -0.2794)
						)
					)
					(width 0)
					(fill yes)
				)
			)
		)
		(pad "2" smd custom
			(at 0 0.4445 270)
			(size 0.1397 0.1397)
			(layers "F.Cu" "F.Mask" "F.Paste")
			(net "IO_EXP5_A1")
			(options
				(clearance outline)
				(anchor circle)
			)
			(primitives
				(gr_poly
					(pts
						(arc
							(start -0.1778 -0.2794)
							(mid -0.249642 -0.249642)
							(end -0.2794 -0.1778)
						)
						(arc
							(start -0.2794 0.1778)
							(mid -0.249642 0.249642)
							(end -0.1778 0.2794)
						)
						(arc
							(start 0.1778 0.2794)
							(mid 0.249642 0.249642)
							(end 0.2794 0.1778)
						)
						(arc
							(start 0.2794 -0.1778)
							(mid 0.249642 -0.249642)
							(end 0.1778 -0.2794)
						)
					)
					(width 0)
					(fill yes)
				)
			)
		)
	)
	(footprint ""
		(layer "F.Cu")
		(at 464.82 -257.81 -90)
		(property "Reference" "R329"
			(at 0 0 270)
			(layer "F.SilkS")
			(hide yes)
			(effects
				(font
					(size 1.27 1.27)
				)
			)
		)
		(property "Value" "300KR2F-GP"
			(at 0.064008 -3.993896 270)
			(unlocked yes)
			(layer "F.Fab")
			(hide yes)
			(effects
				(font
					(size 1.016 1.016)
					(thickness 0.1524)
				)
			)
		)
		(property "Device Type" "R402H16"
			(at 0.064008 -5.517896 270)
			(unlocked yes)
			(layer "F.Fab")
			(hide yes)
			(effects
				(font
					(size 1.016 1.016)
					(thickness 0.1524)
				)
			)
		)
		(duplicate_pad_numbers_are_jumpers no)
		(fp_line
			(start -0.508 -0.9398)
			(end -0.508 0.9398)
			(stroke
				(width 0.1524)
				(type default)
			)
			(layer "F.SilkS")
		)
		(fp_line
			(start 0.508 -0.9398)
			(end -0.508 -0.9398)
			(stroke
				(width 0.1524)
				(type default)
			)
			(layer "F.SilkS")
		)
		(fp_rect
			(start -0.508 0.9398)
			(end 0.508 -0.9398)
			(stroke
				(width 0)
				(type default)
			)
			(fill no)
			(layer "F.CrtYd")
		)
		(fp_rect
			(start -0.508 0.9398)
			(end 0.508 -0.9398)
			(stroke
				(width 0)
				(type default)
			)
			(fill no)
			(layer "F.Fab")
		)
		(pad "1" smd custom
			(at 0 -0.4445 270)
			(size 0.1397 0.1397)
			(layers "F.Cu" "F.Mask" "F.Paste")
			(net "SW_HDD_N10")
			(options
				(clearance outline)
				(anchor circle)
			)
			(primitives
				(gr_poly
					(pts
						(arc
							(start -0.1778 -0.2794)
							(mid -0.249642 -0.249642)
							(end -0.2794 -0.1778)
						)
						(arc
							(start -0.2794 0.1778)
							(mid -0.249642 0.249642)
							(end -0.1778 0.2794)
						)
						(arc
							(start 0.1778 0.2794)
							(mid 0.249642 0.249642)
							(end 0.2794 0.1778)
						)
						(arc
							(start 0.2794 -0.1778)
							(mid 0.249642 -0.249642)
							(end 0.1778 -0.2794)
						)
					)
					(width 0)
					(fill yes)
				)
			)
		)
		(pad "2" smd custom
			(at 0 0.4445 270)
			(size 0.1397 0.1397)
			(layers "F.Cu" "F.Mask" "F.Paste")
			(net "P12V_B")
			(options
				(clearance outline)
				(anchor circle)
			)
			(primitives
				(gr_poly
					(pts
						(arc
							(start -0.1778 -0.2794)
							(mid -0.249642 -0.249642)
							(end -0.2794 -0.1778)
						)
						(arc
							(start -0.2794 0.1778)
							(mid -0.249642 0.249642)
							(end -0.1778 0.2794)
						)
						(arc
							(start 0.1778 0.2794)
							(mid 0.249642 0.249642)
							(end 0.2794 0.1778)
						)
						(arc
							(start 0.2794 -0.1778)
							(mid 0.249642 -0.249642)
							(end 0.1778 -0.2794)
						)
					)
					(width 0)
					(fill yes)
				)
			)
		)
	)
	(footprint ""
		(layer "F.Cu")
		(at 206.756 -348.361 90)
		(property "Reference" "R1018"
			(at 0 0 90)
			(layer "F.SilkS")
			(hide yes)
			(effects
				(font
					(size 1.27 1.27)
				)
			)
		)
		(property "Value" "10R5F-1-GP"
			(at 0 -8.9535 90)
			(unlocked yes)
			(layer "F.Fab")
			(hide yes)
			(effects
				(font
					(size 1.27 1.016)
					(thickness 0.1524)
				)
			)
		)
		(property "Device Type" "R805H24"
			(at 0 -10.6299 90)
			(unlocked yes)
			(layer "F.Fab")
			(hide yes)
			(effects
				(font
					(size 1.27 1.016)
					(thickness 0.1524)
				)
			)
		)
		(duplicate_pad_numbers_are_jumpers no)
		(fp_line
			(start 0.889 -1.7018)
			(end -0.889 -1.7018)
			(stroke
				(width 0.1524)
				(type default)
			)
			(layer "F.SilkS")
		)
		(fp_line
			(start 0.889 -1.7018)
			(end 0.889 -0.381)
			(stroke
				(width 0.1524)
				(type default)
			)
			(layer "F.SilkS")
		)
		(fp_line
			(start -0.889 -1.7018)
			(end -0.889 0.2794)
			(stroke
				(width 0.1524)
				(type default)
			)
			(layer "F.SilkS")
		)
		(fp_line
			(start -0.889 0.0762)
			(end -0.889 1.7018)
			(stroke
				(width 0.1524)
				(type default)
			)
			(layer "F.SilkS")
		)
		(fp_line
			(start 0.889 1.7018)
			(end 0.889 -0.508)
			(stroke
				(width 0.1524)
				(type default)
			)
			(layer "F.SilkS")
		)
		(fp_line
			(start -0.889 1.7018)
			(end 0.889 1.7018)
			(stroke
				(width 0.1524)
				(type default)
			)
			(layer "F.SilkS")
		)
		(fp_poly
			(pts
				(xy 0.9652 -1.778) (xy 0.9652 1.778) (xy -0.9652 1.778) (xy -0.9652 -1.778)
			)
			(stroke
				(width 0)
				(type default)
			)
			(fill no)
			(layer "F.CrtYd")
		)
		(fp_rect
			(start -0.9652 1.778)
			(end 0.9652 -1.778)
			(stroke
				(width 0)
				(type default)
			)
			(fill no)
			(layer "F.Fab")
		)
		(pad "1" smd rect
			(at 0 -0.9652 90)
			(size 1.397 1.143)
			(layers "F.Cu" "F.Mask" "F.Paste")
			(net "MB0_12V_CTRL_GATE4")
		)
		(pad "2" smd rect
			(at 0 0.9652 90)
			(size 1.397 1.143)
			(layers "F.Cu" "F.Mask" "F.Paste")
			(net "MB0_CM_GATE_R")
		)
	)
	(footprint ""
		(layer "F.Cu")
		(at 24.257 -45.466 180)
		(property "Reference" "C348"
			(at 0 0 180)
			(layer "F.SilkS")
			(hide yes)
			(effects
				(font
					(size 1.27 1.27)
				)
			)
		)
		(property "Value" "SC1U25V3KX-GP"
			(at 0 -2.8194 180)
			(unlocked yes)
			(layer "F.Fab")
			(hide yes)
			(effects
				(font
					(size 1.016 1.016)
					(thickness 0.1524)
				)
			)
		)
		(property "Device Type" "C603H36"
			(at 0 -4.3434 180)
			(unlocked yes)
			(layer "F.Fab")
			(hide yes)
			(effects
				(font
					(size 1.016 1.016)
					(thickness 0.1524)
				)
			)
		)
		(duplicate_pad_numbers_are_jumpers no)
		(fp_line
			(start 0.508 0)
			(end -0.508 0)
			(stroke
				(width 0.2032)
				(type default)
			)
			(layer "F.SilkS")
		)
		(fp_rect
			(start -0.5842 1.3335)
			(end 0.5842 -1.3335)
			(stroke
				(width 0)
				(type default)
			)
			(fill no)
			(layer "F.CrtYd")
		)
		(fp_rect
			(start -0.5842 1.3335)
			(end 0.5842 -1.3335)
			(stroke
				(width 0)
				(type default)
			)
			(fill no)
			(layer "F.Fab")
		)
		(pad "1" smd custom
			(at 0 -0.762 180)
			(size 0.2159 0.2159)
			(layers "F.Cu" "F.Mask" "F.Paste")
			(net "P12V_HDD24")
			(options
				(clearance outline)
				(anchor circle)
			)
			(primitives
				(gr_poly
					(pts
						(arc
							(start -0.3302 -0.4318)
							(mid -0.402042 -0.402042)
							(end -0.4318 -0.3302)
						)
						(arc
							(start -0.4318 0.3302)
							(mid -0.402042 0.402042)
							(end -0.3302 0.4318)
						)
						(arc
							(start 0.3302 0.4318)
							(mid 0.402042 0.402042)
							(end 0.4318 0.3302)
						)
						(arc
							(start 0.4318 -0.3302)
							(mid 0.402042 -0.402042)
							(end 0.3302 -0.4318)
						)
					)
					(width 0)
					(fill yes)
				)
			)
		)
		(pad "2" smd custom
			(at 0 0.762 180)
			(size 0.2159 0.2159)
			(layers "F.Cu" "F.Mask" "F.Paste")
			(net "GND")
			(options
				(clearance outline)
				(anchor circle)
			)
			(primitives
				(gr_poly
					(pts
						(arc
							(start -0.3302 -0.4318)
							(mid -0.402042 -0.402042)
							(end -0.4318 -0.3302)
						)
						(arc
							(start -0.4318 0.3302)
							(mid -0.402042 0.402042)
							(end -0.3302 0.4318)
						)
						(arc
							(start 0.3302 0.4318)
							(mid 0.402042 0.402042)
							(end 0.4318 0.3302)
						)
						(arc
							(start 0.4318 -0.3302)
							(mid 0.402042 -0.402042)
							(end 0.3302 -0.4318)
						)
					)
					(width 0)
					(fill yes)
				)
			)
		)
	)
	(footprint ""
		(layer "F.Cu")
		(at 237.236 -219.964 180)
		(property "Reference" "Q17"
			(at 0 0 180)
			(layer "F.SilkS")
			(hide yes)
			(effects
				(font
					(size 1.27 1.27)
				)
			)
		)
		(property "Value" "SSM3K324R-GP"
			(at 0.127 -8.9662 180)
			(unlocked yes)
			(layer "F.Fab")
			(hide yes)
			(effects
				(font
					(size 1.016 1.016)
					(thickness 0.1524)
				)
			)
		)
		(property "Device Type" "SOT23DGS2D4H35"
			(at 0.127 -10.4902 180)
			(unlocked yes)
			(layer "F.Fab")
			(hide yes)
			(effects
				(font
					(size 1.016 1.016)
					(thickness 0.1524)
				)
			)
		)
		(duplicate_pad_numbers_are_jumpers no)
		(fp_line
			(start 1.651 1.778)
			(end 1.651 -1.778)
			(stroke
				(width 0.1524)
				(type default)
			)
			(layer "F.SilkS")
		)
		(fp_line
			(start 1.651 -1.778)
			(end -1.651 -1.778)
			(stroke
				(width 0.1524)
				(type default)
			)
			(layer "F.SilkS")
		)
		(fp_line
			(start -1.651 1.778)
			(end 1.651 1.778)
			(stroke
				(width 0.1524)
				(type default)
			)
			(layer "F.SilkS")
		)
		(fp_line
			(start -1.651 -1.778)
			(end -1.651 1.778)
			(stroke
				(width 0.1524)
				(type default)
			)
			(layer "F.SilkS")
		)
		(fp_poly
			(pts
				(xy -1.778 1.8796) (xy -1.778 -1.8796) (xy 1.778 -1.8796) (xy 1.778 1.8796)
			)
			(stroke
				(width 0)
				(type default)
			)
			(fill no)
			(layer "F.CrtYd")
		)
		(fp_poly
			(pts
				(xy -1.778 1.8796) (xy -1.778 -1.8796) (xy 1.778 -1.8796) (xy 1.778 1.8796)
			)
			(stroke
				(width 0)
				(type default)
			)
			(fill no)
			(layer "F.Fab")
		)
		(pad "D" smd custom
			(at 0 -0.9525 180)
			(size 0.1905 0.1905)
			(layers "F.Cu" "F.Mask" "F.Paste")
			(net "P3V3_STBY_B")
			(options
				(clearance outline)
				(anchor circle)
			)
			(primitives
				(gr_poly
					(pts
						(arc
							(start -0.1778 0.5715)
							(mid -0.321484 0.511984)
							(end -0.381 0.3683)
						)
						(arc
							(start -0.381 -0.3683)
							(mid -0.321484 -0.511984)
							(end -0.1778 -0.5715)
						)
						(arc
							(start 0.1778 -0.5715)
							(mid 0.321484 -0.511984)
							(end 0.381 -0.3683)
						)
						(arc
							(start 0.381 0.3683)
							(mid 0.321484 0.511984)
							(end 0.1778 0.5715)
						)
					)
					(width 0)
					(fill yes)
				)
			)
		)
		(pad "G" smd custom
			(at -0.98425 0.9525 180)
			(size 0.1905 0.1905)
			(layers "F.Cu" "F.Mask" "F.Paste")
			(net "SCC_FULL_PWR_EN_5V")
			(options
				(clearance outline)
				(anchor circle)
			)
			(primitives
				(gr_poly
					(pts
						(arc
							(start -0.1778 0.5715)
							(mid -0.321484 0.511984)
							(end -0.381 0.3683)
						)
						(arc
							(start -0.381 -0.3683)
							(mid -0.321484 -0.511984)
							(end -0.1778 -0.5715)
						)
						(arc
							(start 0.1778 -0.5715)
							(mid 0.321484 -0.511984)
							(end 0.381 -0.3683)
						)
						(arc
							(start 0.381 0.3683)
							(mid 0.321484 0.511984)
							(end 0.1778 0.5715)
						)
					)
					(width 0)
					(fill yes)
				)
			)
		)
		(pad "S" smd custom
			(at 0.98425 0.9525 180)
			(size 0.1905 0.1905)
			(layers "F.Cu" "F.Mask" "F.Paste")
			(net "GPIO_VCC_U8")
			(options
				(clearance outline)
				(anchor circle)
			)
			(primitives
				(gr_poly
					(pts
						(arc
							(start -0.1778 0.5715)
							(mid -0.321484 0.511984)
							(end -0.381 0.3683)
						)
						(arc
							(start -0.381 -0.3683)
							(mid -0.321484 -0.511984)
							(end -0.1778 -0.5715)
						)
						(arc
							(start 0.1778 -0.5715)
							(mid 0.321484 -0.511984)
							(end 0.381 -0.3683)
						)
						(arc
							(start 0.381 0.3683)
							(mid 0.321484 0.511984)
							(end 0.1778 0.5715)
						)
					)
					(width 0)
					(fill yes)
				)
			)
		)
	)
	(footprint ""
		(layer "F.Cu")
		(at 479.384614 -245.219474 -90)
		(property "Reference" "C171"
			(at 0 0 270)
			(layer "F.SilkS")
			(hide yes)
			(effects
				(font
					(size 1.27 1.27)
				)
			)
		)
		(property "Value" "SCD01U16V1KX-GP"
			(at -2.8321 -1.7399 270)
			(unlocked yes)
			(layer "F.Fab")
			(hide yes)
			(effects
				(font
					(size 1.016 1.016)
					(thickness 0.1524)
				)
			)
		)
		(property "Device Type" "C0201H13"
			(at -2.8321 -3.2639 270)
			(unlocked yes)
			(layer "F.Fab")
			(hide yes)
			(effects
				(font
					(size 1.016 1.016)
					(thickness 0.1524)
				)
			)
		)
		(duplicate_pad_numbers_are_jumpers no)
		(fp_rect
			(start -0.2794 0.6477)
			(end 0.2794 -0.6477)
			(stroke
				(width 0)
				(type default)
			)
			(fill no)
			(layer "F.CrtYd")
		)
		(fp_rect
			(start -0.2794 0.6477)
			(end 0.2794 -0.6477)
			(stroke
				(width 0)
				(type default)
			)
			(fill no)
			(layer "F.Fab")
		)
		(pad "1" smd custom
			(at 0 -0.2794 270)
			(size 0.0762 0.0762)
			(layers "F.Cu" "F.Mask" "F.Paste")
			(net "SAS_HDD_RX_N11")
			(options
				(clearance outline)
				(anchor circle)
			)
			(primitives
				(gr_poly
					(pts
						(arc
							(start 0.1524 -0.127)
							(mid 0.137521 -0.162921)
							(end 0.1016 -0.1778)
						)
						(arc
							(start -0.1016 -0.1778)
							(mid -0.137521 -0.162921)
							(end -0.1524 -0.127)
						)
						(arc
							(start -0.1524 0.127)
							(mid -0.137521 0.162921)
							(end -0.1016 0.1778)
						)
						(arc
							(start 0.1016 0.1778)
							(mid 0.137521 0.162921)
							(end 0.1524 0.127)
						)
					)
					(width 0)
					(fill yes)
				)
			)
		)
		(pad "2" smd custom
			(at 0 0.2794 270)
			(size 0.0762 0.0762)
			(layers "F.Cu" "F.Mask" "F.Paste")
			(net "PHY_SCC_B_TO_DRV_B_11_DN")
			(options
				(clearance outline)
				(anchor circle)
			)
			(primitives
				(gr_poly
					(pts
						(arc
							(start 0.1524 -0.127)
							(mid 0.137521 -0.162921)
							(end 0.1016 -0.1778)
						)
						(arc
							(start -0.1016 -0.1778)
							(mid -0.137521 -0.162921)
							(end -0.1524 -0.127)
						)
						(arc
							(start -0.1524 0.127)
							(mid -0.137521 0.162921)
							(end -0.1016 0.1778)
						)
						(arc
							(start 0.1016 0.1778)
							(mid 0.137521 0.162921)
							(end 0.1524 0.127)
						)
					)
					(width 0)
					(fill yes)
				)
			)
		)
	)
	(footprint ""
		(layer "F.Cu")
		(at 353.184714 -130.21945 -90)
		(property "Reference" "C275"
			(at 0 0 270)
			(layer "F.SilkS")
			(hide yes)
			(effects
				(font
					(size 1.27 1.27)
				)
			)
		)
		(property "Value" "SCD01U16V1KX-GP"
			(at -2.8321 -1.7399 270)
			(unlocked yes)
			(layer "F.Fab")
			(hide yes)
			(effects
				(font
					(size 1.016 1.016)
					(thickness 0.1524)
				)
			)
		)
		(property "Device Type" "C0201H13"
			(at -2.8321 -3.2639 270)
			(unlocked yes)
			(layer "F.Fab")
			(hide yes)
			(effects
				(font
					(size 1.016 1.016)
					(thickness 0.1524)
				)
			)
		)
		(duplicate_pad_numbers_are_jumpers no)
		(fp_rect
			(start -0.2794 0.6477)
			(end 0.2794 -0.6477)
			(stroke
				(width 0)
				(type default)
			)
			(fill no)
			(layer "F.CrtYd")
		)
		(fp_rect
			(start -0.2794 0.6477)
			(end 0.2794 -0.6477)
			(stroke
				(width 0)
				(type default)
			)
			(fill no)
			(layer "F.Fab")
		)
		(pad "1" smd custom
			(at 0 -0.2794 270)
			(size 0.0762 0.0762)
			(layers "F.Cu" "F.Mask" "F.Paste")
			(net "SAS_HDD_RX_N19")
			(options
				(clearance outline)
				(anchor circle)
			)
			(primitives
				(gr_poly
					(pts
						(arc
							(start 0.1524 -0.127)
							(mid 0.137521 -0.162921)
							(end 0.1016 -0.1778)
						)
						(arc
							(start -0.1016 -0.1778)
							(mid -0.137521 -0.162921)
							(end -0.1524 -0.127)
						)
						(arc
							(start -0.1524 0.127)
							(mid -0.137521 0.162921)
							(end -0.1016 0.1778)
						)
						(arc
							(start 0.1016 0.1778)
							(mid 0.137521 0.162921)
							(end 0.1524 0.127)
						)
					)
					(width 0)
					(fill yes)
				)
			)
		)
		(pad "2" smd custom
			(at 0 0.2794 270)
			(size 0.0762 0.0762)
			(layers "F.Cu" "F.Mask" "F.Paste")
			(net "PHY_SCC_B_TO_DRV_B_19_DN")
			(options
				(clearance outline)
				(anchor circle)
			)
			(primitives
				(gr_poly
					(pts
						(arc
							(start 0.1524 -0.127)
							(mid 0.137521 -0.162921)
							(end 0.1016 -0.1778)
						)
						(arc
							(start -0.1016 -0.1778)
							(mid -0.137521 -0.162921)
							(end -0.1524 -0.127)
						)
						(arc
							(start -0.1524 0.127)
							(mid -0.137521 0.162921)
							(end -0.1016 0.1778)
						)
						(arc
							(start 0.1016 0.1778)
							(mid 0.137521 0.162921)
							(end 0.1524 0.127)
						)
					)
					(width 0)
					(fill yes)
				)
			)
		)
	)
)
